(kicad_pcb
	(version 20260206)
	(generator "pcbnew")
	(generator_version "10.0")
	(general
		(thickness 1.6)
		(legacy_teardrops no)
	)
	(paper "A4")
	(title_block
		(title "Bryce Canyon_Front Panel_16369-1_OCP.brd")
		(comment 1 "Bryce Canyon / footprints 116-121 of 154")
	)
	(layers
		(0 "F.Cu" signal "TOP")
		(4 "In1.Cu" signal "L2GND")
		(6 "In2.Cu" signal "L3VCC")
		(2 "B.Cu" signal "BOTTOM")
		(9 "F.Adhes" user "F.Adhesive")
		(11 "B.Adhes" user "B.Adhesive")
		(13 "F.Paste" user "Package Geometry/Pastemask Top")
		(15 "B.Paste" user "Package Geometry/Pastemask Bottom")
		(5 "F.SilkS" user "Ref Des/Silkscreen Top")
		(7 "B.SilkS" user "Ref Des/Silkscreen Bottom")
		(1 "F.Mask" user "Board Geometry/Soldermask Top")
		(3 "B.Mask" user "Board Geometry/Soldermask Bottom")
		(17 "Dwgs.User" user "User.Drawings")
		(19 "Cmts.User" user "User.Comments")
		(21 "Eco1.User" user "User.Eco1")
		(23 "Eco2.User" user "User.Eco2")
		(25 "Edge.Cuts" user "Board Geometry/Outline")
		(27 "Margin" user)
		(31 "F.CrtYd" user "Package Geometry/Place Bound Top")
		(29 "B.CrtYd" user "Package Geometry/Place Bound Bottom")
		(35 "F.Fab" user "Ref Des/Assembly Top")
		(33 "B.Fab" user "Ref Des/Assembly Bottom")
	)
	(footprint ""
		(layer "F.Cu")
		(at 55.4482 -9.525 180)
		(property "Reference" "R72"
			(at 0 0 180)
			(layer "F.SilkS")
			(hide yes)
			(effects
				(font
					(size 1.27 1.27)
				)
			)
		)
		(property "Value" "4K7R2F-GP"
			(at 0.064008 -3.993896 180)
			(unlocked yes)
			(layer "F.Fab")
			(hide yes)
			(effects
				(font
					(size 1.016 1.016)
					(thickness 0.1524)
				)
			)
		)
		(property "Device Type" "R402H16"
			(at 0.064008 -5.517896 180)
			(unlocked yes)
			(layer "F.Fab")
			(hide yes)
			(effects
				(font
					(size 1.016 1.016)
					(thickness 0.1524)
				)
			)
		)
		(duplicate_pad_numbers_are_jumpers no)
		(fp_line
			(start 0.508 -0.9398)
			(end -0.508 -0.9398)
			(stroke
				(width 0.1524)
				(type default)
			)
			(layer "F.SilkS")
		)
		(fp_line
			(start -0.508 -0.9398)
			(end -0.508 0.9398)
			(stroke
				(width 0.1524)
				(type default)
			)
			(layer "F.SilkS")
		)
		(fp_rect
			(start -0.508 0.9398)
			(end 0.508 -0.9398)
			(stroke
				(width 0)
				(type default)
			)
			(fill no)
			(layer "F.CrtYd")
		)
		(fp_rect
			(start -0.508 0.9398)
			(end 0.508 -0.9398)
			(stroke
				(width 0)
				(type default)
			)
			(fill no)
			(layer "F.Fab")
		)
		(pad "1" smd custom
			(at 0 -0.4445 180)
			(size 0.1397 0.1397)
			(layers "F.Cu" "F.Mask" "F.Paste")
			(net "P3V3_STBY_B")
			(options
				(clearance outline)
				(anchor circle)
			)
			(primitives
				(gr_poly
					(pts
						(arc
							(start -0.1778 -0.2794)
							(mid -0.249642 -0.249642)
							(end -0.2794 -0.1778)
						)
						(arc
							(start -0.2794 0.1778)
							(mid -0.249642 0.249642)
							(end -0.1778 0.2794)
						)
						(arc
							(start 0.1778 0.2794)
							(mid 0.249642 0.249642)
							(end 0.2794 0.1778)
						)
						(arc
							(start 0.2794 -0.1778)
							(mid 0.249642 -0.249642)
							(end 0.1778 -0.2794)
						)
					)
					(width 0)
					(fill yes)
				)
			)
		)
		(pad "2" smd custom
			(at 0 0.4445 180)
			(size 0.1397 0.1397)
			(layers "F.Cu" "F.Mask" "F.Paste")
			(net "TCA9555_B_A1")
			(options
				(clearance outline)
				(anchor circle)
			)
			(primitives
				(gr_poly
					(pts
						(arc
							(start -0.1778 -0.2794)
							(mid -0.249642 -0.249642)
							(end -0.2794 -0.1778)
						)
						(arc
							(start -0.2794 0.1778)
							(mid -0.249642 0.249642)
							(end -0.1778 0.2794)
						)
						(arc
							(start 0.1778 0.2794)
							(mid 0.249642 0.249642)
							(end 0.2794 0.1778)
						)
						(arc
							(start 0.2794 -0.1778)
							(mid 0.249642 -0.249642)
							(end 0.1778 -0.2794)
						)
					)
					(width 0)
					(fill yes)
				)
			)
		)
	)
	(footprint ""
		(layer "F.Cu")
		(at 8.199882 -34.99993)
		(property "Reference" "SW3"
			(at 0 0 0)
			(layer "F.SilkS")
			(hide yes)
			(effects
				(font
					(size 1.27 1.27)
				)
			)
		)
		(property "Value" "SW-TACT-4P-214-GP"
			(at 5.97154 0.7747 0)
			(unlocked yes)
			(layer "F.Fab")
			(hide yes)
			(effects
				(font
					(size 2.54 2.54)
					(thickness 0.381)
				)
			)
		)
		(property "Device Type" "DTSM-62N-Q-TR"
			(at 5.97154 -0.7493 0)
			(unlocked yes)
			(layer "F.Fab")
			(hide yes)
			(effects
				(font
					(size 2.54 2.54)
					(thickness 0.381)
				)
			)
		)
		(duplicate_pad_numbers_are_jumpers no)
		(fp_line
			(start -5.0927 -2.8956)
			(end -5.0927 -1.6002)
			(stroke
				(width 0.3302)
				(type default)
			)
			(layer "F.SilkS")
		)
		(fp_line
			(start -5.0038 -3.3528)
			(end 5.0038 -3.3528)
			(stroke
				(width 0.1524)
				(type default)
			)
			(layer "F.SilkS")
		)
		(fp_line
			(start -5.0038 -1.3462)
			(end -5.0038 -3.3528)
			(stroke
				(width 0.1524)
				(type default)
			)
			(layer "F.SilkS")
		)
		(fp_line
			(start -5.0038 1.3462)
			(end -3.3528 1.3462)
			(stroke
				(width 0.1524)
				(type default)
			)
			(layer "F.SilkS")
		)
		(fp_line
			(start -5.0038 3.3528)
			(end -5.0038 1.3462)
			(stroke
				(width 0.1524)
				(type default)
			)
			(layer "F.SilkS")
		)
		(fp_line
			(start -3.3528 -1.3462)
			(end -5.0038 -1.3462)
			(stroke
				(width 0.1524)
				(type default)
			)
			(layer "F.SilkS")
		)
		(fp_line
			(start -3.3528 1.3462)
			(end -3.3528 -1.3462)
			(stroke
				(width 0.1524)
				(type default)
			)
			(layer "F.SilkS")
		)
		(fp_line
			(start 3.3528 -1.3462)
			(end 3.3528 1.3462)
			(stroke
				(width 0.1524)
				(type default)
			)
			(layer "F.SilkS")
		)
		(fp_line
			(start 3.3528 1.3462)
			(end 5.0038 1.3462)
			(stroke
				(width 0.1524)
				(type default)
			)
			(layer "F.SilkS")
		)
		(fp_line
			(start 5.0038 -3.3528)
			(end 5.0038 -1.3462)
			(stroke
				(width 0.1524)
				(type default)
			)
			(layer "F.SilkS")
		)
		(fp_line
			(start 5.0038 -1.3462)
			(end 3.3528 -1.3462)
			(stroke
				(width 0.1524)
				(type default)
			)
			(layer "F.SilkS")
		)
		(fp_line
			(start 5.0038 1.3462)
			(end 5.0038 3.3528)
			(stroke
				(width 0.1524)
				(type default)
			)
			(layer "F.SilkS")
		)
		(fp_line
			(start 5.0038 3.3528)
			(end -5.0038 3.3528)
			(stroke
				(width 0.1524)
				(type default)
			)
			(layer "F.SilkS")
		)
		(fp_poly
			(pts
				(xy -5.072888 -2.29108) (xy -5.707888 -1.65608) (xy -5.707888 -2.92608)
			)
			(stroke
				(width 0)
				(type default)
			)
			(fill yes)
			(layer "F.SilkS")
		)
		(fp_poly
			(pts
				(xy -3.0988 3.0988) (xy -3.0988 2.5908) (xy -4.4958 2.5908) (xy -4.4958 1.8796) (xy -3.0988 1.8796)
				(xy -3.0988 -1.8796) (xy -4.4958 -1.8796) (xy -4.4958 -2.5908) (xy -3.0988 -2.5908) (xy -3.0988 -3.0988)
				(xy 3.0988 -3.0988) (xy 3.0988 -2.5908) (xy 4.4958 -2.5908) (xy 4.4958 -1.8796) (xy 3.0988 -1.8796)
				(xy 3.0988 1.8796) (xy 4.4958 1.8796) (xy 4.4958 2.5908) (xy 3.0988 2.5908) (xy 3.0988 3.0988)
			)
			(stroke
				(width 0)
				(type default)
			)
			(fill no)
			(layer "F.CrtYd")
		)
		(fp_poly
			(pts
				(xy -5.2578 3.6068) (xy -5.2578 1.0922) (xy -3.6068 1.0922) (xy -3.6068 -1.0922) (xy -5.2578 -1.0922)
				(xy -5.2578 -3.6068) (xy 5.2578 -3.6068) (xy 5.2578 -1.0922) (xy 3.6068 -1.0922) (xy 3.6068 -0.00635)
				(xy 3.0988 -0.00635) (xy 3.0988 -1.8796) (xy 4.4958 -1.8796) (xy 4.4958 -2.5908) (xy 3.0988 -2.5908)
				(xy 3.0988 -3.0988) (xy -3.0988 -3.0988) (xy -3.0988 -2.5908) (xy -4.4958 -2.5908) (xy -4.4958 -1.8796)
				(xy -3.0988 -1.8796) (xy -3.0988 1.8796) (xy -4.4958 1.8796) (xy -4.4958 2.5908) (xy -3.0988 2.5908)
				(xy -3.0988 3.0988) (xy 3.0988 3.0988) (xy 3.0988 2.5908) (xy 4.4958 2.5908) (xy 4.4958 1.8796)
				(xy 3.0988 1.8796) (xy 3.0988 0.00635) (xy 3.6068 0.00635) (xy 3.6068 1.0922) (xy 5.2578 1.0922)
				(xy 5.2578 3.6068)
			)
			(stroke
				(width 0)
				(type default)
			)
			(fill no)
			(layer "F.CrtYd")
		)
		(fp_poly
			(pts
				(xy -5.2578 3.6068) (xy -5.2578 1.0922) (xy -3.6068 1.0922) (xy -3.6068 -1.0922) (xy -5.2578 -1.0922)
				(xy -5.2578 -3.6068) (xy 5.2578 -3.6068) (xy 5.2578 -1.0922) (xy 3.6068 -1.0922) (xy 3.6068 1.0922)
				(xy 5.2578 1.0922) (xy 5.2578 3.6068)
			)
			(stroke
				(width 0)
				(type default)
			)
			(fill no)
			(layer "F.Fab")
		)
		(pad "T1" smd rect
			(at -3.9751 -2.249932)
			(size 1.5494 1.2954)
			(layers "F.Cu" "F.Mask" "F.Paste")
			(net "SYS_RESET_BTN_A")
		)
		(pad "T2" smd rect
			(at 3.9751 -2.249932)
			(size 1.5494 1.2954)
			(layers "F.Cu" "F.Mask" "F.Paste")
			(net "SYS_RESET_BTN_A")
		)
		(pad "T3" smd rect
			(at -3.9751 2.249932)
			(size 1.5494 1.2954)
			(layers "F.Cu" "F.Mask" "F.Paste")
			(net "GND")
		)
		(pad "T4" smd rect
			(at 3.9751 2.249932)
			(size 1.5494 1.2954)
			(layers "F.Cu" "F.Mask" "F.Paste")
			(net "GND")
		)
	)
	(footprint ""
		(layer "F.Cu")
		(at 14.3002 -12.573 90)
		(property "Reference" "U1"
			(at 0 0 90)
			(layer "F.SilkS")
			(hide yes)
			(effects
				(font
					(size 1.27 1.27)
				)
			)
		)
		(property "Value" "TS5A23157DGSR-GP"
			(at 0 -11.811 90)
			(unlocked yes)
			(layer "F.Fab")
			(hide yes)
			(effects
				(font
					(size 2.54 2.54)
					(thickness 0.381)
				)
			)
		)
		(property "Device Type" "MSOP10H44"
			(at 0 -13.335 90)
			(unlocked yes)
			(layer "F.Fab")
			(hide yes)
			(effects
				(font
					(size 2.54 2.54)
					(thickness 0.381)
				)
			)
		)
		(duplicate_pad_numbers_are_jumpers no)
		(fp_line
			(start 1.143 -1.016)
			(end 1.143 1.016)
			(stroke
				(width 0.1524)
				(type default)
			)
			(layer "F.SilkS")
		)
		(fp_line
			(start -2.0066 -1.016)
			(end 1.143 -1.016)
			(stroke
				(width 0.1524)
				(type default)
			)
			(layer "F.SilkS")
		)
		(fp_line
			(start -1.5748 0)
			(end -1.9558 -0.381)
			(stroke
				(width 0.1524)
				(type default)
			)
			(layer "F.SilkS")
		)
		(fp_line
			(start -1.5748 0)
			(end -1.9558 0.381)
			(stroke
				(width 0.1524)
				(type default)
			)
			(layer "F.SilkS")
		)
		(fp_line
			(start 1.143 1.016)
			(end -2.0066 1.016)
			(stroke
				(width 0.1524)
				(type default)
			)
			(layer "F.SilkS")
		)
		(fp_line
			(start -1.8288 1.016)
			(end -1.8288 3.048)
			(stroke
				(width 0.508)
				(type default)
			)
			(layer "F.SilkS")
		)
		(fp_line
			(start -2.0066 1.016)
			(end -2.0066 -1.016)
			(stroke
				(width 0.1524)
				(type default)
			)
			(layer "F.SilkS")
		)
		(fp_poly
			(pts
				(xy -2.0828 3.3401) (xy 2.0828 3.3401) (xy 2.0828 -3.3401) (xy -2.0828 -3.3401)
			)
			(stroke
				(width 0)
				(type default)
			)
			(fill no)
			(layer "F.CrtYd")
		)
		(fp_poly
			(pts
				(xy -2.0828 3.3401) (xy 2.0828 3.3401) (xy 2.0828 -3.3401) (xy -2.0828 -3.3401)
			)
			(stroke
				(width 0)
				(type default)
			)
			(fill no)
			(layer "F.Fab")
		)
		(pad "1" smd rect
			(at -0.99949 2.0701 90)
			(size 0.3048 1.524)
			(layers "F.Cu" "F.Mask" "F.Paste")
			(net "UART_SEL_A_MUX_R")
		)
		(pad "2" smd rect
			(at -0.50038 2.0701 90)
			(size 0.3048 1.524)
			(layers "F.Cu" "F.Mask" "F.Paste")
			(net "UART_EXP_A_TX")
		)
		(pad "3" smd rect
			(at 0 2.0701 90)
			(size 0.3048 1.524)
			(layers "F.Cu" "F.Mask" "F.Paste")
			(net "GND")
		)
		(pad "4" smd rect
			(at 0.50038 2.0701 90)
			(size 0.3048 1.524)
			(layers "F.Cu" "F.Mask" "F.Paste")
			(net "UART_EXP_A_RX")
		)
		(pad "5" smd rect
			(at 0.99949 2.0701 90)
			(size 0.3048 1.524)
			(layers "F.Cu" "F.Mask" "F.Paste")
			(net "UART_SEL_A_MUX_R")
		)
		(pad "6" smd rect
			(at 0.99949 -2.0701 90)
			(size 0.3048 1.524)
			(layers "F.Cu" "F.Mask" "F.Paste")
			(net "UART_A_RX")
		)
		(pad "7" smd rect
			(at 0.50038 -2.0701 90)
			(size 0.3048 1.524)
			(layers "F.Cu" "F.Mask" "F.Paste")
			(net "UART_IOC_A_RX")
		)
		(pad "8" smd rect
			(at 0 -2.0701 90)
			(size 0.3048 1.524)
			(layers "F.Cu" "F.Mask" "F.Paste")
			(net "P3V3_STBY_A")
		)
		(pad "9" smd rect
			(at -0.50038 -2.0701 90)
			(size 0.3048 1.524)
			(layers "F.Cu" "F.Mask" "F.Paste")
			(net "UART_IOC_A_TX")
		)
		(pad "10" smd rect
			(at -0.99949 -2.0701 90)
			(size 0.3048 1.524)
			(layers "F.Cu" "F.Mask" "F.Paste")
			(net "UART_A_TX")
		)
	)
	(footprint ""
		(layer "F.Cu")
		(at 46.609 -10.541 180)
		(property "Reference" "C6"
			(at 0 0 180)
			(layer "F.SilkS")
			(hide yes)
			(effects
				(font
					(size 1.27 1.27)
				)
			)
		)
		(property "Value" "SCD1U16V2KX-3GP"
			(at 1.1811 -3.3909 180)
			(unlocked yes)
			(layer "F.Fab")
			(hide yes)
			(effects
				(font
					(size 2.54 2.54)
					(thickness 0.381)
				)
			)
		)
		(property "Device Type" "C402H22"
			(at 1.1811 -4.9149 180)
			(unlocked yes)
			(layer "F.Fab")
			(hide yes)
			(effects
				(font
					(size 2.54 2.54)
					(thickness 0.381)
				)
			)
		)
		(duplicate_pad_numbers_are_jumpers no)
		(fp_rect
			(start -0.4318 0.9525)
			(end 0.4318 -0.9525)
			(stroke
				(width 0)
				(type default)
			)
			(fill no)
			(layer "F.CrtYd")
		)
		(fp_rect
			(start -0.4318 0.9525)
			(end 0.4318 -0.9525)
			(stroke
				(width 0)
				(type default)
			)
			(fill no)
			(layer "F.Fab")
		)
		(pad "1" smd custom
			(at 0 -0.4445 180)
			(size 0.1524 0.1524)
			(layers "F.Cu" "F.Mask" "F.Paste")
			(net "P3V3_STBY_B")
			(options
				(clearance outline)
				(anchor circle)
			)
			(primitives
				(gr_poly
					(pts
						(arc
							(start 0.3048 -0.2032)
							(mid 0.275042 -0.275042)
							(end 0.2032 -0.3048)
						)
						(arc
							(start -0.2032 -0.3048)
							(mid -0.275042 -0.275042)
							(end -0.3048 -0.2032)
						)
						(arc
							(start -0.3048 0.2032)
							(mid -0.275042 0.275042)
							(end -0.2032 0.3048)
						)
						(arc
							(start 0.2032 0.3048)
							(mid 0.275042 0.275042)
							(end 0.3048 0.2032)
						)
					)
					(width 0)
					(fill yes)
				)
			)
		)
		(pad "2" smd custom
			(at 0 0.4445 180)
			(size 0.1524 0.1524)
			(layers "F.Cu" "F.Mask" "F.Paste")
			(net "GND")
			(options
				(clearance outline)
				(anchor circle)
			)
			(primitives
				(gr_poly
					(pts
						(arc
							(start 0.3048 -0.2032)
							(mid 0.275042 -0.275042)
							(end 0.2032 -0.3048)
						)
						(arc
							(start -0.2032 -0.3048)
							(mid -0.275042 -0.275042)
							(end -0.3048 -0.2032)
						)
						(arc
							(start -0.3048 0.2032)
							(mid -0.275042 0.275042)
							(end -0.2032 0.3048)
						)
						(arc
							(start 0.2032 0.3048)
							(mid 0.275042 0.275042)
							(end 0.3048 0.2032)
						)
					)
					(width 0)
					(fill yes)
				)
			)
		)
	)
	(footprint ""
		(layer "F.Cu")
		(at 29.550106 -19.99996 90)
		(property "Reference" "SCW1"
			(at 0 0 90)
			(layer "F.SilkS")
			(hide yes)
			(effects
				(font
					(size 1.27 1.27)
				)
			)
		)
		(property "Value" "STFT363B238R224H453-GP"
			(at 7.0612 0.7747 90)
			(unlocked yes)
			(layer "F.Fab")
			(hide yes)
			(effects
				(font
					(size 2.54 2.54)
					(thickness 0.381)
				)
			)
		)
		(property "Device Type" "STFT363B238R224H453"
			(at 7.0612 -0.7493 90)
			(unlocked yes)
			(layer "F.Fab")
			(hide yes)
			(effects
				(font
					(size 2.54 2.54)
					(thickness 0.381)
				)
			)
		)
		(duplicate_pad_numbers_are_jumpers no)
		(fp_circle
			(center 0 0)
			(end 0 5.3594)
			(stroke
				(width 0.3048)
				(type default)
			)
			(fill no)
			(layer "F.SilkS")
		)
		(fp_poly
			(pts
				(arc
					(start 0 3.5306)
					(mid 0 -3.5306)
					(end 0 3.5306)
				)
			)
			(stroke
				(width 0)
				(type default)
			)
			(fill no)
			(layer "B.CrtYd")
		)
		(fp_poly
			(pts
				(arc
					(start 0 5.0038)
					(mid 0 -5.0038)
					(end 0 5.0038)
				)
			)
			(stroke
				(width 0)
				(type default)
			)
			(fill no)
			(layer "F.CrtYd")
		)
		(fp_poly
			(pts
				(arc
					(start 5.5118 0.00635)
					(mid -5.511804 0)
					(end 5.5118 -0.00635)
				)
				(arc
					(start 5.0038 -0.00635)
					(mid -5.003804 0)
					(end 5.0038 0.00635)
				)
			)
			(stroke
				(width 0)
				(type default)
			)
			(fill no)
			(layer "F.CrtYd")
		)
		(fp_poly
			(pts
				(arc
					(start 0 3.5306)
					(mid 0 -3.5306)
					(end 0 3.5306)
				)
			)
			(stroke
				(width 0)
				(type default)
			)
			(fill no)
			(layer "B.Fab")
		)
		(fp_poly
			(pts
				(arc
					(start 0 5.5118)
					(mid 0 -5.5118)
					(end 0 5.5118)
				)
			)
			(stroke
				(width 0)
				(type default)
			)
			(fill no)
			(layer "F.Fab")
		)
		(pad "1" thru_hole circle
			(at 0 0 90)
			(size 9.2202 9.2202)
			(drill 5.6896)
			(layers "*.Cu" "*.Mask")
			(remove_unused_layers no)
			(net "Net_76")
			(clearance -1.2573)
			(thermal_gap 0.3302)
			(padstack
				(mode front_inner_back)
				(layer "Inner"
					(shape circle)
					(size 6.0452 6.0452)
					(clearance 0.3302)
				)
				(layer "B.Cu"
					(shape circle)
					(size 6.0452 6.0452)
					(clearance 0.3302)
				)
			)
		)
	)
	(footprint ""
		(layer "F.Cu")
		(at 11.303 -7.4168)
		(property "Reference" "U10"
			(at 0 0 0)
			(layer "F.SilkS")
			(hide yes)
			(effects
				(font
					(size 1.27 1.27)
				)
			)
		)
		(property "Value" "SNLVC1G126DCKR-GP"
			(at -2.3368 -8.6868 0)
			(unlocked yes)
			(layer "F.Fab")
			(hide yes)
			(effects
				(font
					(size 1.016 1.016)
					(thickness 0.1524)
				)
			)
		)
		(property "Device Type" "SC70-5H44"
			(at -2.3114 -10.414 0)
			(unlocked yes)
			(layer "F.Fab")
			(hide yes)
			(effects
				(font
					(size 1.016 1.016)
					(thickness 0.1524)
				)
			)
		)
		(duplicate_pad_numbers_are_jumpers no)
		(fp_line
			(start -1.27 -1.7018)
			(end 1.27 -1.7018)
			(stroke
				(width 0.1524)
				(type default)
			)
			(layer "F.SilkS")
		)
		(fp_line
			(start -1.27 1.7018)
			(end -1.27 -1.7018)
			(stroke
				(width 0.1524)
				(type default)
			)
			(layer "F.SilkS")
		)
		(fp_line
			(start 0.6604 -1.8034)
			(end 1.3843 -1.8034)
			(stroke
				(width 0.3302)
				(type default)
			)
			(layer "F.SilkS")
		)
		(fp_line
			(start 1.27 -1.7018)
			(end 1.27 1.7018)
			(stroke
				(width 0.1524)
				(type default)
			)
			(layer "F.SilkS")
		)
		(fp_line
			(start 1.27 1.7018)
			(end -1.27 1.7018)
			(stroke
				(width 0.1524)
				(type default)
			)
			(layer "F.SilkS")
		)
		(fp_line
			(start 1.3843 -1.8034)
			(end 1.3843 -1.1176)
			(stroke
				(width 0.3302)
				(type default)
			)
			(layer "F.SilkS")
		)
		(fp_rect
			(start -1.524 1.9558)
			(end 1.524 -1.9558)
			(stroke
				(width 0)
				(type default)
			)
			(fill no)
			(layer "F.CrtYd")
		)
		(fp_poly
			(pts
				(xy -1.524 -1.9558) (xy 1.524 -1.9558) (xy 1.524 1.9558) (xy -1.524 1.9558)
			)
			(stroke
				(width 0)
				(type default)
			)
			(fill no)
			(layer "F.Fab")
		)
		(pad "1" smd rect
			(at 0.65024 -0.8255)
			(size 0.4064 1.2192)
			(layers "F.Cu" "F.Mask" "F.Paste")
			(net "DEBUG_CARD_A_PRSNT")
		)
		(pad "2" smd rect
			(at 0 -0.8255)
			(size 0.4064 1.2192)
			(layers "F.Cu" "F.Mask" "F.Paste")
			(net "UART_A_TX")
		)
		(pad "3" smd rect
			(at -0.65024 -0.8255)
			(size 0.4064 1.2192)
			(layers "F.Cu" "F.Mask" "F.Paste")
			(net "GND")
		)
		(pad "4" smd rect
			(at -0.65024 0.8255)
			(size 0.4064 1.2192)
			(layers "F.Cu" "F.Mask" "F.Paste")
			(net "UART_DEBUG_A_TX")
		)
		(pad "5" smd rect
			(at 0.65024 0.8255)
			(size 0.4064 1.2192)
			(layers "F.Cu" "F.Mask" "F.Paste")
			(net "P3V3_STBY_A")
		)
	)
)
